# T6G (Grand Teton) — schematic netlist excerpt (pin names and nets, part order shuffled) for the footprints in the layout excerpt that follows; sources: Cadence DE-HDL packaged netlist, KiCad conversion of 04192023_DAF0TMB3IC0_F0TG_MB_C_brd_V02_OCP.brd

PC347_SOP1_3  Q_CAP  2.2UF 10V 10% X6S  pkg C0402  page 216 : A = PVDDCR_CPU0_P1_PVCC ; B = GND
R3720  Q_RES  0 5% CHIP  pkg 0402LF  page 252 : A = SMB_LM75_2_3V3AUX_SDA_R ; B = SMB_LM75_2_3V3AUX_SDA

(kicad_pcb
	(version 20260206)
	(generator "pcbnew")
	(generator_version "10.0")
	(general
		(thickness 1.6)
		(legacy_teardrops no)
	)
	(paper "A4")
	(title_block
		(title "04192023_DAF0TMB3IC0_F0TG_MB_C_brd_V02_OCP.brd")
		(comment 1 "Grand Teton / footprints 981-982 of 8354")
	)
	(layers
		(0 "F.Cu" signal "TOP")
		(4 "In1.Cu" signal "GND")
		(6 "In2.Cu" signal "IN1")
		(8 "In3.Cu" signal "GND1")
		(10 "In4.Cu" signal "IN2")
		(12 "In5.Cu" signal "GND2")
		(14 "In6.Cu" signal "IN3")
		(16 "In7.Cu" signal "GND3")
		(18 "In8.Cu" signal "VCC")
		(20 "In9.Cu" signal "VCC1")
		(22 "In10.Cu" signal "GND4")
		(24 "In11.Cu" signal "IN4")
		(26 "In12.Cu" signal "GND5")
		(28 "In13.Cu" signal "IN5")
		(30 "In14.Cu" signal "GND6")
		(32 "In15.Cu" signal "IN6")
		(34 "In16.Cu" signal "GND7")
		(2 "B.Cu" signal "BOTTOM")
		(9 "F.Adhes" user "F.Adhesive")
		(11 "B.Adhes" user "B.Adhesive")
		(13 "F.Paste" user "Package Geometry/Pastemask Top")
		(15 "B.Paste" user "Package Geometry/Pastemask Bottom")
		(5 "F.SilkS" user "Ref Des/Silkscreen Top")
		(7 "B.SilkS" user "Ref Des/Silkscreen Bottom")
		(1 "F.Mask" user "Board Geometry/Soldermask Top")
		(3 "B.Mask" user "Board Geometry/Soldermask Bottom")
		(17 "Dwgs.User" user "User.Drawings")
		(19 "Cmts.User" user "User.Comments")
		(21 "Eco1.User" user "User.Eco1")
		(23 "Eco2.User" user "User.Eco2")
		(25 "Edge.Cuts" user "Board Geometry/Outline")
		(27 "Margin" user)
		(31 "F.CrtYd" user "Package Geometry/Place Bound Top")
		(29 "B.CrtYd" user "Package Geometry/Place Bound Bottom")
		(35 "F.Fab" user "Ref Des/Assembly Top")
		(33 "B.Fab" user "Ref Des/Assembly Bottom")
	)
	(footprint ""
		(layer "F.Cu")
		(at 257.242056 -115.86337 180)
		(property "Reference" "R3720"
			(at 0 0 180)
			(layer "F.SilkS")
			(hide yes)
			(effects
				(font
					(size 1.27 1.27)
				)
			)
		)
		(property "Value" ""
			(at 0 0 180)
			(layer "F.Fab")
			(effects
				(font
					(size 1.27 1.27)
				)
			)
		)
		(duplicate_pad_numbers_are_jumpers no)
		(fp_line
			(start 0.7874 0.4064)
			(end -0.7874 0.4064)
			(stroke
				(width 0.1524)
				(type default)
			)
			(layer "F.SilkS")
		)
		(fp_line
			(start 0.7874 -0.4064)
			(end 0.7874 0.4064)
			(stroke
				(width 0.1524)
				(type default)
			)
			(layer "F.SilkS")
		)
		(fp_line
			(start -0.7874 0.4064)
			(end -0.7874 -0.4064)
			(stroke
				(width 0.1524)
				(type default)
			)
			(layer "F.SilkS")
		)
		(fp_line
			(start -0.7874 -0.4064)
			(end 0.7874 -0.4064)
			(stroke
				(width 0.1524)
				(type default)
			)
			(layer "F.SilkS")
		)
		(fp_line
			(start 0.67945 0.3048)
			(end 0.120396 0.3048)
			(stroke
				(width 0.1)
				(type default)
			)
			(layer "F.Fab")
		)
		(fp_line
			(start 0.67945 -0.3048)
			(end 0.67945 0.3048)
			(stroke
				(width 0.1)
				(type default)
			)
			(layer "F.Fab")
		)
		(fp_line
			(start 0.12065 -0.2794)
			(end 0.12065 -0.3048)
			(stroke
				(width 0.1)
				(type default)
			)
			(layer "F.Fab")
		)
		(fp_line
			(start 0.12065 -0.3048)
			(end 0.67945 -0.3048)
			(stroke
				(width 0.1)
				(type default)
			)
			(layer "F.Fab")
		)
		(fp_line
			(start 0.120396 0.3048)
			(end 0.120396 0.2794)
			(stroke
				(width 0.1)
				(type default)
			)
			(layer "F.Fab")
		)
		(fp_line
			(start 0.120396 0.2794)
			(end -0.12065 0.2794)
			(stroke
				(width 0.1)
				(type default)
			)
			(layer "F.Fab")
		)
		(fp_line
			(start -0.12065 0.3048)
			(end -0.67945 0.3048)
			(stroke
				(width 0.1)
				(type default)
			)
			(layer "F.Fab")
		)
		(fp_line
			(start -0.12065 0.2794)
			(end -0.12065 0.3048)
			(stroke
				(width 0.1)
				(type default)
			)
			(layer "F.Fab")
		)
		(fp_line
			(start -0.12065 -0.2794)
			(end 0.12065 -0.2794)
			(stroke
				(width 0.1)
				(type default)
			)
			(layer "F.Fab")
		)
		(fp_line
			(start -0.12065 -0.305054)
			(end -0.12065 -0.2794)
			(stroke
				(width 0.1)
				(type default)
			)
			(layer "F.Fab")
		)
		(fp_line
			(start -0.67945 0.3048)
			(end -0.67945 -0.305054)
			(stroke
				(width 0.1)
				(type default)
			)
			(layer "F.Fab")
		)
		(fp_line
			(start -0.67945 -0.305054)
			(end -0.12065 -0.305054)
			(stroke
				(width 0.1)
				(type default)
			)
			(layer "F.Fab")
		)
		(pad "1" smd circle
			(at -0.40005 0 180)
			(size 0 0)
			(layers "F.Cu" "F.Mask" "F.Paste")
			(net "SMB_LM75_2_3V3AUX_SDA_R")
		)
		(pad "2" smd circle
			(at 0.40005 0 180)
			(size 0 0)
			(layers "F.Cu" "F.Mask" "F.Paste")
			(net "SMB_LM75_2_3V3AUX_SDA")
		)
	)
	(footprint ""
		(layer "F.Cu")
		(at 136.10717 -156.532834 90)
		(property "Reference" "PC347_SOP1_3"
			(at 0 0 90)
			(layer "F.SilkS")
			(hide yes)
			(effects
				(font
					(size 1.27 1.27)
				)
			)
		)
		(property "Value" ""
			(at 0 0 90)
			(layer "F.Fab")
			(effects
				(font
					(size 1.27 1.27)
				)
			)
		)
		(duplicate_pad_numbers_are_jumpers no)
		(fp_line
			(start 0.7874 -0.4064)
			(end 0.7874 0.4064)
			(stroke
				(width 0.1524)
				(type default)
			)
			(layer "F.SilkS")
		)
		(fp_line
			(start -0.7874 -0.4064)
			(end 0.7874 -0.4064)
			(stroke
				(width 0.1524)
				(type default)
			)
			(layer "F.SilkS")
		)
		(fp_line
			(start 0.7874 0.4064)
			(end -0.7874 0.4064)
			(stroke
				(width 0.1524)
				(type default)
			)
			(layer "F.SilkS")
		)
		(fp_line
			(start -0.7874 0.4064)
			(end -0.7874 -0.4064)
			(stroke
				(width 0.1524)
				(type default)
			)
			(layer "F.SilkS")
		)
		(fp_line
			(start -0.12065 -0.305054)
			(end -0.12065 -0.2794)
			(stroke
				(width 0.1)
				(type default)
			)
			(layer "F.Fab")
		)
		(fp_line
			(start -0.67945 -0.305054)
			(end -0.12065 -0.305054)
			(stroke
				(width 0.1)
				(type default)
			)
			(layer "F.Fab")
		)
		(fp_line
			(start 0.67945 -0.3048)
			(end 0.67945 0.3048)
			(stroke
				(width 0.1)
				(type default)
			)
			(layer "F.Fab")
		)
		(fp_line
			(start 0.12065 -0.3048)
			(end 0.67945 -0.3048)
			(stroke
				(width 0.1)
				(type default)
			)
			(layer "F.Fab")
		)
		(fp_line
			(start 0.12065 -0.2794)
			(end 0.12065 -0.3048)
			(stroke
				(width 0.1)
				(type default)
			)
			(layer "F.Fab")
		)
		(fp_line
			(start -0.12065 -0.2794)
			(end 0.12065 -0.2794)
			(stroke
				(width 0.1)
				(type default)
			)
			(layer "F.Fab")
		)
		(fp_line
			(start 0.120396 0.2794)
			(end -0.12065 0.2794)
			(stroke
				(width 0.1)
				(type default)
			)
			(layer "F.Fab")
		)
		(fp_line
			(start -0.12065 0.2794)
			(end -0.12065 0.3048)
			(stroke
				(width 0.1)
				(type default)
			)
			(layer "F.Fab")
		)
		(fp_line
			(start 0.67945 0.3048)
			(end 0.120396 0.3048)
			(stroke
				(width 0.1)
				(type default)
			)
			(layer "F.Fab")
		)
		(fp_line
			(start 0.120396 0.3048)
			(end 0.120396 0.2794)
			(stroke
				(width 0.1)
				(type default)
			)
			(layer "F.Fab")
		)
		(fp_line
			(start -0.12065 0.3048)
			(end -0.67945 0.3048)
			(stroke
				(width 0.1)
				(type default)
			)
			(layer "F.Fab")
		)
		(fp_line
			(start -0.67945 0.3048)
			(end -0.67945 -0.305054)
			(stroke
				(width 0.1)
				(type default)
			)
			(layer "F.Fab")
		)
		(pad "1" smd circle
			(at -0.40005 0 90)
			(size 0 0)
			(layers "F.Cu" "F.Mask" "F.Paste")
			(net "PVDDCR_CPU0_P1_PVCC")
		)
		(pad "2" smd circle
			(at 0.40005 0 90)
			(size 0 0)
			(layers "F.Cu" "F.Mask" "F.Paste")
			(net "GND")
		)
	)
)
